FILE_TYPE = CONNECTIVITY;
{Allegro Design Entry HDL 16.6-p007 (v16-6-112F) 10/10/2012}
"PAGE_NUMBER" = 59;
0"NC";
1"M_J_DQS_DP<17:0>";
2"M_J_DQS_DN<17:0>";
3"M_J_MA<17:0>";
4"M_J_BA<1:0>";
5"M_J_BG<1:0>";
6"M_J_CKE <3:0>";
7"M_J_CS_N<7:0>";
8"M_J_ODT<3:0>";
9"M_J_DQ<63:0>";
10"M_J_CLK_DN<3:0>";
11"M_J_CLK_DP<3:0>";
12"M_J_ECC<7:0>";
13"M_J_C<2>";
14"M_J_ECC<0>";
15"M_J_ECC<1>";
16"M_J_ECC<2>";
17"M_J_ECC<3>";
18"M_J_ECC<4>";
19"M_J_ECC<5>";
20"M_J_ECC<6>";
21"M_J_ECC<7>";
22"M_J_DQ<0>";
23"M_J_DQ<1>";
24"M_J_DQ<2>";
25"M_J_DQ<3>";
26"M_J_DQ<4>";
27"M_J_DQ<5>";
28"M_J_DQ<6>";
29"M_J_DQ<7>";
30"M_J_DQ<8>";
31"M_J_DQ<9>";
32"M_J_DQ<10>";
33"M_J_CLK_DP<0>";
34"M_J_CLK_DP<1>";
35"M_J_CLK_DP<2>";
36"M_J_CLK_DP<3>";
37"M_J_CLK_DN<0>";
38"M_J_CLK_DN<1>";
39"M_J_CLK_DN<2>";
40"M_J_CLK_DN<3>";
41"M_J_DQ<11>";
42"M_J_DQ<12>";
43"M_J_DQ<13>";
44"M_J_DQ<14>";
45"M_J_DQ<15>";
46"M_J_DQ<16>";
47"M_J_DQ<17>";
48"M_J_DQ<18>";
49"M_J_DQ<19>";
50"M_J_DQ<20>";
51"M_J_DQ<21>";
52"M_J_DQ<22>";
53"M_J_DQ<23>";
54"M_J_DQ<24>";
55"M_J_DQ<25>";
56"M_J_DQ<26>";
57"M_J_DQ<27>";
58"M_J_DQ<28>";
59"M_J_DQ<29>";
60"M_J_DQ<30>";
61"M_J_DQ<31>";
62"M_J_DQ<32>";
63"M_J_DQ<33>";
64"M_J_DQ<34>";
65"M_J_DQ<35>";
66"M_J_DQ<36>";
67"M_J_DQ<37>";
68"M_J_DQ<38>";
69"M_J_DQ<39>";
70"M_J_DQ<40>";
71"M_J_DQ<41>";
72"M_J_DQ<42>";
73"M_J_DQ<43>";
74"M_J_DQ<44>";
75"M_J_DQ<45>";
76"M_J_DQ<46>";
77"M_J_DQ<47>";
78"M_J_DQ<48>";
79"M_J_DQ<49>";
80"M_J_DQ<50>";
81"M_J_DQ<51>";
82"M_J_DQ<52>";
83"M_J_DQ<53>";
84"M_J_DQ<54>";
85"M_J_DQ<55>";
86"M_J_DQ<56>";
87"M_J_DQ<57>";
88"M_J_DQ<58>";
89"M_J_DQ<59>";
90"M_J_DQ<60>";
91"M_J_DQ<61>";
92"M_J_DQ<62>";
93"M_J_DQ<63>";
94"M_J_ODT<0>";
95"M_J_ODT<1>";
96"M_J_ODT<2>";
97"M_J_ODT<3>";
98"M_J_MA<0>";
99"M_J_MA<1>";
100"M_J_MA<2>";
101"M_J_CS_N<0>";
102"M_J_CS_N<1>";
103"M_J_CS_N<2>";
104"M_J_CS_N<3>";
105"M_J_CS_N<4>";
106"M_J_CS_N<5>";
107"M_J_CS_N<6>";
108"M_J_CS_N<7>";
109"M_J_CKE <0>";
110"M_J_CKE <1>";
111"M_J_CKE <2>";
112"M_J_CKE <3>";
113"M_J_BG<0>";
114"M_J_BG<1>";
115"M_J_BA<0>";
116"M_J_BA<1>";
117"M_J_MA<3>";
118"M_J_MA<4>";
119"M_J_MA<5>";
120"M_J_MA<6>";
121"M_J_MA<7>";
122"M_J_MA<8>";
123"M_J_MA<9>";
124"M_J_MA<10>";
125"M_J_MA<11>";
126"M_J_MA<12>";
127"M_J_MA<13>";
128"M_J_MA<14>";
129"M_J_MA<15>";
130"M_J_MA<16>";
131"M_J_MA<17>";
132"M_J_DQS_DP<0>";
133"M_J_DQS_DP<1>";
134"M_J_DQS_DP<2>";
135"M_J_DQS_DP<3>";
136"M_J_DQS_DP<4>";
137"M_J_DQS_DP<5>";
138"M_J_DQS_DN<0>";
139"M_J_DQS_DN<1>";
140"M_J_DQS_DN<2>";
141"M_J_DQS_DN<3>";
142"M_J_DQS_DN<4>";
143"M_J_DQS_DN<5>";
144"M_J_DQS_DN<6>";
145"M_J_DQS_DN<7>";
146"M_J_DQS_DN<8>";
147"M_J_DQS_DN<9>";
148"M_J_DQS_DN<10>";
149"M_J_DQS_DN<11>";
150"M_J_DQS_DN<12>";
151"M_J_DQS_DN<13>";
152"M_J_DQS_DN<14>";
153"M_J_DQS_DN<15>";
154"M_J_DQS_DN<16>";
155"M_J_DQS_DN<17>";
156"M_J_PAR";
157"M_J_ALERT_N";
158"M_J_ACT_N";
159"M_J_DQS_DP<6>";
160"M_J_DQS_DP<7>";
161"M_J_DQS_DP<8>";
162"M_J_DQS_DP<9>";
163"M_J_DQS_DP<10>";
164"M_J_DQS_DP<11>";
165"M_J_DQS_DP<12>";
166"M_J_DQS_DP<13>";
167"M_J_DQS_DP<14>";
168"M_J_DQS_DP<15>";
169"M_J_DQS_DP<16>";
170"M_J_DQS_DP<17>";
%"TAP"
"6","(-5575,800)","0","mstr_standard","I10";
;
HDL_TAP"TRUE"
BODY_TYPE"PLUMBING"
CDS_LIB"mstr_standard";
"B \NAC \NWC"11;
"S \NAC"
BN"0"33;
%"TAP"
"6","(-2850,1550)","2","mstr_standard","I100";
;
HDL_TAP"TRUE"
BODY_TYPE"PLUMBING"
CDS_LIB"mstr_standard";
"B \NAC \NWC"8;
"S \NAC"
BN"3"97;
%"TAP"
"6","(-2850,1500)","2","mstr_standard","I101";
;
HDL_TAP"TRUE"
BODY_TYPE"PLUMBING"
CDS_LIB"mstr_standard";
"B \NAC \NWC"8;
"S \NAC"
BN"2"96;
%"TAP"
"6","(-2850,1450)","2","mstr_standard","I102";
;
HDL_TAP"TRUE"
BODY_TYPE"PLUMBING"
CDS_LIB"mstr_standard";
"B \NAC \NWC"8;
"S \NAC"
BN"1"95;
%"TAP"
"6","(-2850,1650)","2","mstr_standard","I103";
;
HDL_TAP"TRUE"
BODY_TYPE"PLUMBING"
CDS_LIB"mstr_standard";
"B \NAC \NWC"6;
"S \NAC"
BN"0"109;
%"TAP"
"6","(-2850,1700)","2","mstr_standard","I104";
;
HDL_TAP"TRUE"
BODY_TYPE"PLUMBING"
CDS_LIB"mstr_standard";
"B \NAC \NWC"6;
"S \NAC"
BN"1"110;
%"TAP"
"6","(-2850,1750)","2","mstr_standard","I105";
;
HDL_TAP"TRUE"
BODY_TYPE"PLUMBING"
CDS_LIB"mstr_standard";
"B \NAC \NWC"6;
"S \NAC"
BN"2"111;
%"TAP"
"6","(-2850,1800)","2","mstr_standard","I106";
;
HDL_TAP"TRUE"
BODY_TYPE"PLUMBING"
CDS_LIB"mstr_standard";
"B \NAC \NWC"6;
"S \NAC"
BN"3"112;
%"TAP"
"6","(-2850,1900)","2","mstr_standard","I107";
;
HDL_TAP"TRUE"
BODY_TYPE"PLUMBING"
CDS_LIB"mstr_standard";
"B \NAC \NWC"3;
"S \NAC"
BN"0"98;
%"TAP"
"6","(-2850,1950)","2","mstr_standard","I108";
;
HDL_TAP"TRUE"
BODY_TYPE"PLUMBING"
CDS_LIB"mstr_standard";
"B \NAC \NWC"3;
"S \NAC"
BN"1"99;
%"TAP"
"6","(-2850,2050)","2","mstr_standard","I109";
;
HDL_TAP"TRUE"
BODY_TYPE"PLUMBING"
CDS_LIB"mstr_standard";
"B \NAC \NWC"3;
"S \NAC"
BN"3"117;
%"TAP"
"6","(-5575,900)","0","mstr_standard","I11";
;
HDL_TAP"TRUE"
BODY_TYPE"PLUMBING"
CDS_LIB"mstr_standard";
"B \NAC \NWC"11;
"S \NAC"
BN"2"35;
%"TAP"
"6","(-2850,2000)","2","mstr_standard","I110";
;
HDL_TAP"TRUE"
BODY_TYPE"PLUMBING"
CDS_LIB"mstr_standard";
"B \NAC \NWC"3;
"S \NAC"
BN"2"100;
%"TAP"
"6","(-2850,2100)","2","mstr_standard","I111";
;
HDL_TAP"TRUE"
BODY_TYPE"PLUMBING"
CDS_LIB"mstr_standard";
"B \NAC \NWC"3;
"S \NAC"
BN"4"118;
%"TAP"
"6","(-2850,2150)","2","mstr_standard","I112";
;
HDL_TAP"TRUE"
BODY_TYPE"PLUMBING"
CDS_LIB"mstr_standard";
"B \NAC \NWC"3;
"S \NAC"
BN"5"119;
%"TAP"
"6","(-2850,2200)","2","mstr_standard","I113";
;
HDL_TAP"TRUE"
BODY_TYPE"PLUMBING"
CDS_LIB"mstr_standard";
"B \NAC \NWC"3;
"S \NAC"
BN"6"120;
%"TAP"
"6","(-2850,2300)","2","mstr_standard","I114";
;
HDL_TAP"TRUE"
BODY_TYPE"PLUMBING"
CDS_LIB"mstr_standard";
"B \NAC \NWC"3;
"S \NAC"
BN"8"122;
%"TAP"
"6","(-2850,2250)","2","mstr_standard","I115";
;
HDL_TAP"TRUE"
BODY_TYPE"PLUMBING"
CDS_LIB"mstr_standard";
"B \NAC \NWC"3;
"S \NAC"
BN"7"121;
%"TAP"
"6","(-2850,2450)","2","mstr_standard","I116";
;
HDL_TAP"TRUE"
BODY_TYPE"PLUMBING"
CDS_LIB"mstr_standard";
"B \NAC \NWC"3;
"S \NAC"
BN"11"125;
%"TAP"
"6","(-2850,2400)","2","mstr_standard","I117";
;
HDL_TAP"TRUE"
BODY_TYPE"PLUMBING"
CDS_LIB"mstr_standard";
"B \NAC \NWC"3;
"S \NAC"
BN"10"124;
%"TAP"
"6","(-2850,2350)","2","mstr_standard","I118";
;
HDL_TAP"TRUE"
BODY_TYPE"PLUMBING"
CDS_LIB"mstr_standard";
"B \NAC \NWC"3;
"S \NAC"
BN"9"123;
%"TAP"
"6","(-2850,2500)","2","mstr_standard","I119";
;
HDL_TAP"TRUE"
BODY_TYPE"PLUMBING"
CDS_LIB"mstr_standard";
"B \NAC \NWC"3;
"S \NAC"
BN"12"126;
%"TAP"
"6","(-5575,950)","0","mstr_standard","I12";
;
HDL_TAP"TRUE"
BODY_TYPE"PLUMBING"
CDS_LIB"mstr_standard";
"B \NAC \NWC"11;
"S \NAC"
BN"3"36;
%"TAP"
"6","(-2850,2550)","2","mstr_standard","I120";
;
HDL_TAP"TRUE"
BODY_TYPE"PLUMBING"
CDS_LIB"mstr_standard";
"B \NAC \NWC"3;
"S \NAC"
BN"13"127;
%"TAP"
"6","(-2850,2600)","2","mstr_standard","I121";
;
HDL_TAP"TRUE"
BODY_TYPE"PLUMBING"
CDS_LIB"mstr_standard";
"B \NAC \NWC"3;
"S \NAC"
BN"14"128;
%"TAP"
"6","(-2850,2650)","2","mstr_standard","I122";
;
HDL_TAP"TRUE"
BODY_TYPE"PLUMBING"
CDS_LIB"mstr_standard";
"B \NAC \NWC"3;
"S \NAC"
BN"15"129;
%"TAP"
"6","(-2850,2700)","2","mstr_standard","I123";
;
HDL_TAP"TRUE"
BODY_TYPE"PLUMBING"
CDS_LIB"mstr_standard";
"B \NAC \NWC"3;
"S \NAC"
BN"16"130;
%"TAP"
"6","(-2850,2750)","2","mstr_standard","I124";
;
HDL_TAP"TRUE"
BODY_TYPE"PLUMBING"
CDS_LIB"mstr_standard";
"B \NAC \NWC"3;
"S \NAC"
BN"17"131;
%"TAP"
"6","(-2850,2900)","2","mstr_standard","I125";
;
HDL_TAP"TRUE"
BODY_TYPE"PLUMBING"
CDS_LIB"mstr_standard";
"B \NAC \NWC"2;
"S \NAC"
BN"1"139;
%"TAP"
"6","(-2850,2950)","2","mstr_standard","I126";
;
HDL_TAP"TRUE"
BODY_TYPE"PLUMBING"
CDS_LIB"mstr_standard";
"B \NAC \NWC"2;
"S \NAC"
BN"2"140;
%"TAP"
"6","(-2850,2850)","2","mstr_standard","I127";
;
HDL_TAP"TRUE"
BODY_TYPE"PLUMBING"
CDS_LIB"mstr_standard";
"B \NAC \NWC"2;
"S \NAC"
BN"0"138;
%"TAP"
"6","(-2850,3050)","2","mstr_standard","I128";
;
HDL_TAP"TRUE"
BODY_TYPE"PLUMBING"
CDS_LIB"mstr_standard";
"B \NAC \NWC"2;
"S \NAC"
BN"4"142;
%"TAP"
"6","(-2850,3000)","2","mstr_standard","I129";
;
HDL_TAP"TRUE"
BODY_TYPE"PLUMBING"
CDS_LIB"mstr_standard";
"B \NAC \NWC"2;
"S \NAC"
BN"3"141;
%"TAP"
"6","(-5575,1050)","0","mstr_standard","I13";
;
HDL_TAP"TRUE"
BODY_TYPE"PLUMBING"
CDS_LIB"mstr_standard";
"B \NAC \NWC"12;
"S \NAC"
BN"0"14;
%"TAP"
"6","(-2850,3100)","2","mstr_standard","I130";
;
HDL_TAP"TRUE"
BODY_TYPE"PLUMBING"
CDS_LIB"mstr_standard";
"B \NAC \NWC"2;
"S \NAC"
BN"5"143;
%"TAP"
"6","(-2850,3150)","2","mstr_standard","I131";
;
HDL_TAP"TRUE"
BODY_TYPE"PLUMBING"
CDS_LIB"mstr_standard";
"B \NAC \NWC"2;
"S \NAC"
BN"6"144;
%"TAP"
"6","(-2850,3200)","2","mstr_standard","I132";
;
HDL_TAP"TRUE"
BODY_TYPE"PLUMBING"
CDS_LIB"mstr_standard";
"B \NAC \NWC"2;
"S \NAC"
BN"7"145;
%"TAP"
"6","(-2850,3250)","2","mstr_standard","I133";
;
HDL_TAP"TRUE"
BODY_TYPE"PLUMBING"
CDS_LIB"mstr_standard";
"B \NAC \NWC"2;
"S \NAC"
BN"8"146;
%"TAP"
"6","(-2850,3300)","2","mstr_standard","I134";
;
HDL_TAP"TRUE"
BODY_TYPE"PLUMBING"
CDS_LIB"mstr_standard";
"B \NAC \NWC"2;
"S \NAC"
BN"9"147;
%"TAP"
"6","(-2850,3350)","2","mstr_standard","I135";
;
HDL_TAP"TRUE"
BODY_TYPE"PLUMBING"
CDS_LIB"mstr_standard";
"B \NAC \NWC"2;
"S \NAC"
BN"10"148;
%"TAP"
"6","(-2850,3450)","2","mstr_standard","I136";
;
HDL_TAP"TRUE"
BODY_TYPE"PLUMBING"
CDS_LIB"mstr_standard";
"B \NAC \NWC"2;
"S \NAC"
BN"12"150;
%"TAP"
"6","(-2850,3400)","2","mstr_standard","I137";
;
HDL_TAP"TRUE"
BODY_TYPE"PLUMBING"
CDS_LIB"mstr_standard";
"B \NAC \NWC"2;
"S \NAC"
BN"11"149;
%"TAP"
"6","(-2850,3600)","2","mstr_standard","I138";
;
HDL_TAP"TRUE"
BODY_TYPE"PLUMBING"
CDS_LIB"mstr_standard";
"B \NAC \NWC"2;
"S \NAC"
BN"15"153;
%"TAP"
"6","(-2850,3550)","2","mstr_standard","I139";
;
HDL_TAP"TRUE"
BODY_TYPE"PLUMBING"
CDS_LIB"mstr_standard";
"B \NAC \NWC"2;
"S \NAC"
BN"14"152;
%"TAP"
"6","(-5575,1100)","0","mstr_standard","I14";
;
HDL_TAP"TRUE"
BODY_TYPE"PLUMBING"
CDS_LIB"mstr_standard";
"B \NAC \NWC"12;
"S \NAC"
BN"1"15;
%"TAP"
"6","(-2850,3500)","2","mstr_standard","I140";
;
HDL_TAP"TRUE"
BODY_TYPE"PLUMBING"
CDS_LIB"mstr_standard";
"B \NAC \NWC"2;
"S \NAC"
BN"13"151;
%"TAP"
"6","(-2850,3650)","2","mstr_standard","I141";
;
HDL_TAP"TRUE"
BODY_TYPE"PLUMBING"
CDS_LIB"mstr_standard";
"B \NAC \NWC"2;
"S \NAC"
BN"16"154;
%"TAP"
"6","(-2850,3700)","2","mstr_standard","I142";
;
HDL_TAP"TRUE"
BODY_TYPE"PLUMBING"
CDS_LIB"mstr_standard";
"B \NAC \NWC"2;
"S \NAC"
BN"17"155;
%"TAP"
"6","(-2850,3800)","2","mstr_standard","I143";
;
HDL_TAP"TRUE"
BODY_TYPE"PLUMBING"
CDS_LIB"mstr_standard";
"B \NAC \NWC"1;
"S \NAC"
BN"0"132;
%"TAP"
"6","(-2850,3850)","2","mstr_standard","I144";
;
HDL_TAP"TRUE"
BODY_TYPE"PLUMBING"
CDS_LIB"mstr_standard";
"B \NAC \NWC"1;
"S \NAC"
BN"1"133;
%"TAP"
"6","(-2850,3900)","2","mstr_standard","I145";
;
HDL_TAP"TRUE"
BODY_TYPE"PLUMBING"
CDS_LIB"mstr_standard";
"B \NAC \NWC"1;
"S \NAC"
BN"2"134;
%"TAP"
"6","(-2850,3950)","2","mstr_standard","I146";
;
HDL_TAP"TRUE"
BODY_TYPE"PLUMBING"
CDS_LIB"mstr_standard";
"B \NAC \NWC"1;
"S \NAC"
BN"3"135;
%"TAP"
"6","(-5575,1150)","0","mstr_standard","I15";
;
HDL_TAP"TRUE"
BODY_TYPE"PLUMBING"
CDS_LIB"mstr_standard";
"B \NAC \NWC"12;
"S \NAC"
BN"2"16;
%"TAP"
"6","(-2850,4000)","2","mstr_standard","I157";
;
HDL_TAP"TRUE"
BODY_TYPE"PLUMBING"
CDS_LIB"mstr_standard";
"B \NAC \NWC"1;
"S \NAC"
BN"4"136;
%"TAP"
"6","(-2850,4100)","2","mstr_standard","I158";
;
HDL_TAP"TRUE"
BODY_TYPE"PLUMBING"
CDS_LIB"mstr_standard";
"B \NAC \NWC"1;
"S \NAC"
BN"6"159;
%"TAP"
"6","(-2850,4050)","2","mstr_standard","I159";
;
HDL_TAP"TRUE"
BODY_TYPE"PLUMBING"
CDS_LIB"mstr_standard";
"B \NAC \NWC"1;
"S \NAC"
BN"5"137;
%"TAP"
"6","(-5575,1250)","0","mstr_standard","I16";
;
HDL_TAP"TRUE"
BODY_TYPE"PLUMBING"
CDS_LIB"mstr_standard";
"B \NAC \NWC"12;
"S \NAC"
BN"4"18;
%"TAP"
"6","(-2850,4150)","2","mstr_standard","I160";
;
HDL_TAP"TRUE"
BODY_TYPE"PLUMBING"
CDS_LIB"mstr_standard";
"B \NAC \NWC"1;
"S \NAC"
BN"7"160;
%"TAP"
"6","(-2850,4200)","2","mstr_standard","I161";
;
HDL_TAP"TRUE"
BODY_TYPE"PLUMBING"
CDS_LIB"mstr_standard";
"B \NAC \NWC"1;
"S \NAC"
BN"8"161;
%"TAP"
"6","(-2850,4250)","2","mstr_standard","I162";
;
HDL_TAP"TRUE"
BODY_TYPE"PLUMBING"
CDS_LIB"mstr_standard";
"B \NAC \NWC"1;
"S \NAC"
BN"9"162;
%"TAP"
"6","(-2850,4300)","2","mstr_standard","I163";
;
HDL_TAP"TRUE"
BODY_TYPE"PLUMBING"
CDS_LIB"mstr_standard";
"B \NAC \NWC"1;
"S \NAC"
BN"10"163;
%"TAP"
"6","(-2850,4350)","2","mstr_standard","I164";
;
HDL_TAP"TRUE"
BODY_TYPE"PLUMBING"
CDS_LIB"mstr_standard";
"B \NAC \NWC"1;
"S \NAC"
BN"11"164;
%"TAP"
"6","(-2850,4500)","2","mstr_standard","I165";
;
HDL_TAP"TRUE"
BODY_TYPE"PLUMBING"
CDS_LIB"mstr_standard";
"B \NAC \NWC"1;
"S \NAC"
BN"14"167;
%"TAP"
"6","(-2850,4450)","2","mstr_standard","I166";
;
HDL_TAP"TRUE"
BODY_TYPE"PLUMBING"
CDS_LIB"mstr_standard";
"B \NAC \NWC"1;
"S \NAC"
BN"13"166;
%"TAP"
"6","(-2850,4400)","2","mstr_standard","I167";
;
HDL_TAP"TRUE"
BODY_TYPE"PLUMBING"
CDS_LIB"mstr_standard";
"B \NAC \NWC"1;
"S \NAC"
BN"12"165;
%"TAP"
"6","(-2850,4550)","2","mstr_standard","I168";
;
HDL_TAP"TRUE"
BODY_TYPE"PLUMBING"
CDS_LIB"mstr_standard";
"B \NAC \NWC"1;
"S \NAC"
BN"15"168;
%"TAP"
"6","(-2850,4600)","2","mstr_standard","I169";
;
HDL_TAP"TRUE"
BODY_TYPE"PLUMBING"
CDS_LIB"mstr_standard";
"B \NAC \NWC"1;
"S \NAC"
BN"16"169;
%"TAP"
"6","(-5575,1200)","0","mstr_standard","I17";
;
HDL_TAP"TRUE"
BODY_TYPE"PLUMBING"
CDS_LIB"mstr_standard";
"B \NAC \NWC"12;
"S \NAC"
BN"3"17;
%"TAP"
"6","(-2850,4650)","2","mstr_standard","I170";
;
HDL_TAP"TRUE"
BODY_TYPE"PLUMBING"
CDS_LIB"mstr_standard";
"B \NAC \NWC"1;
"S \NAC"
BN"17"170;
%"SKX_EXT_B"
"5","(-4175,2550)","0","chpset_lib","I172";
;
CDS_SEC"5"
CDS_LOCATION"U2D1"
SEC"5"
CDS_LIB"chpset_lib"
SEC_TYPE"BGA1"
PACK_TYPE"BGA1"
MATERIAL"IC"
PART_NUMBER"TBD"
LOCATION"U2D1";
"DDR2_PAR"
$PN"V53"156;
"DDR2_ODT<0>"
$PN"AA50"94;
"DDR2_ODT<1>"
$PN"AA48"95;
"DDR2_ODT<2>"
$PN"V49"96;
"DDR2_ODT<3>"
$PN"AB47"97;
"DDR2_MA<0>"
$PN"AB53"98;
"DDR2_MA<1>"
$PN"AE58"99;
"DDR2_MA<2>"
$PN"AD57"100;
"DDR2_MA<3>"
$PN"W58"117;
"DDR2_MA<4>"
$PN"AA58"118;
"DDR2_MA<5>"
$PN"V59"119;
"DDR2_MA<6>"
$PN"AB59"120;
"DDR2_MA<7>"
$PN"AE60"121;
"DDR2_MA<8>"
$PN"AD59"122;
"DDR2_MA<9>"
$PN"AG58"123;
"DDR2_MA<10>"
$PN"AD55"124;
"DDR2_MA<11>"
$PN"AG60"125;
"DDR2_MA<12>"
$PN"AG62"126;
"DDR2_MA<13>"
$PN"AD53"127;
"DDR2_MA<14>"
$PN"W50"128;
"DDR2_MA<15>"
$PN"AE54"129;
"DDR2_MA<16>"
$PN"AA52"130;
"DDR2_MA<17>"
$PN"AC46"131;
"DDR2_ECC<0>"
$PN"AU72"14;
"DDR2_ECC<1>"
$PN"BA72"15;
"DDR2_ECC<2>"
$PN"AV69"16;
"DDR2_ECC<3>"
$PN"AY69"17;
"DDR2_ECC<4>"
$PN"AV73"18;
"DDR2_ECC<5>"
$PN"AY73"19;
"DDR2_ECC<6>"
$PN"AU70"20;
"DDR2_ECC<7>"
$PN"BA70"21;
"DDR2_DQS_DP<0>"
$PN"AM75"132;
"DDR2_DQS_DP<1>"
$PN"AB75"133;
"DDR2_DQS_DP<2>"
$PN"W70"134;
"DDR2_DQS_DP<3>"
$PN"AR66"135;
"DDR2_DQS_DP<4>"
$PN"Y39"136;
"DDR2_DQS_DP<5>"
$PN"Y33"137;
"DDR2_DQS_DP<6>"
$PN"AG30"159;
"DDR2_DQS_DP<7>"
$PN"AG24"160;
"DDR2_DQS_DP<8>"
$PN"AY71"161;
"DDR2_DQS_DP<9>"
$PN"AN76"162;
"DDR2_DQS_DP<10>"
$PN"AC76"163;
"DDR2_DQS_DP<11>"
$PN"V71"164;
"DDR2_DQS_DP<12>"
$PN"AN66"165;
"DDR2_DQS_DP<13>"
$PN"V39"166;
"DDR2_DQS_DP<14>"
$PN"V33"167;
"DDR2_DQS_DP<15>"
$PN"AE30"168;
"DDR2_DQS_DP<16>"
$PN"AE24"169;
"DDR2_DQS_DP<17>"
$PN"AV71"170;
"DDR2_DQS_DN<0>"
$PN"AL74"138;
"DDR2_DQS_DN<1>"
$PN"AA74"139;
"DDR2_DQS_DN<2>"
$PN"Y69"140;
"DDR2_DQS_DN<3>"
$PN"AU66"141;
"DDR2_DQS_DN<4>"
$PN"AB39"142;
"DDR2_DQS_DN<5>"
$PN"AB33"143;
"DDR2_DQS_DN<6>"
$PN"AJ30"144;
"DDR2_DQS_DN<7>"
$PN"AJ24"145;
"DDR2_DQS_DN<8>"
$PN"BB71"146;
"DDR2_DQS_DN<9>"
$PN"AP77"147;
"DDR2_DQS_DN<10>"
$PN"AD77"148;
"DDR2_DQS_DN<11>"
$PN"U72"149;
"DDR2_DQS_DN<12>"
$PN"AL66"150;
"DDR2_DQS_DN<13>"
$PN"T39"151;
"DDR2_DQS_DN<14>"
$PN"T33"152;
"DDR2_DQS_DN<15>"
$PN"AC30"153;
"DDR2_DQS_DN<16>"
$PN"AC24"154;
"DDR2_DQS_DN<17>"
$PN"AT71"155;
"DDR2_DQ<0>"
$PN"AR76"22;
"DDR2_DQ<1>"
$PN"AN74"23;
"DDR2_DQ<2>"
$PN"AK77"24;
"DDR2_DQ<3>"
$PN"AJ76"25;
"DDR2_DQ<4>"
$PN"AT75"26;
"DDR2_DQ<5>"
$PN"AR74"27;
"DDR2_DQ<6>"
$PN"AM77"28;
"DDR2_DQ<7>"
$PN"AK75"29;
"DDR2_DQ<8>"
$PN"AE76"30;
"DDR2_DQ<9>"
$PN"AC74"31;
"DDR2_DQ<10>"
$PN"Y77"32;
"DDR2_DQ<11>"
$PN"W76"41;
"DDR2_DQ<12>"
$PN"AF75"42;
"DDR2_DQ<13>"
$PN"AE74"43;
"DDR2_DQ<14>"
$PN"AB77"44;
"DDR2_DQ<15>"
$PN"Y75"45;
"DDR2_DQ<16>"
$PN"W72"46;
"DDR2_DQ<17>"
$PN"AA70"47;
"DDR2_DQ<18>"
$PN"R70"48;
"DDR2_DQ<19>"
$PN"T69"49;
"DDR2_DQ<20>"
$PN"AA72"50;
"DDR2_DQ<21>"
$PN"AB71"51;
"DDR2_DQ<22>"
$PN"T71"52;
"DDR2_DQ<23>"
$PN"V69"53;
"DDR2_DQ<24>"
$PN"AM67"54;
"DDR2_DQ<25>"
$PN"AT67"55;
"DDR2_DQ<26>"
$PN"AN64"56;
"DDR2_DQ<27>"
$PN"AR64"57;
"DDR2_DQ<28>"
$PN"AN68"58;
"DDR2_DQ<29>"
$PN"AR68"59;
"DDR2_DQ<30>"
$PN"AM65"60;
"DDR2_DQ<31>"
$PN"AT65"61;
"DDR2_DQ<32>"
$PN"U40"62;
"DDR2_DQ<33>"
$PN"AA40"63;
"DDR2_DQ<34>"
$PN"V37"64;
"DDR2_DQ<35>"
$PN"Y37"65;
"DDR2_DQ<36>"
$PN"V41"66;
"DDR2_DQ<37>"
$PN"Y41"67;
"DDR2_DQ<38>"
$PN"U38"68;
"DDR2_DQ<39>"
$PN"AA38"69;
"DDR2_DQ<40>"
$PN"U34"70;
"DDR2_DQ<41>"
$PN"AA34"71;
"DDR2_DQ<42>"
$PN"V31"72;
"DDR2_DQ<43>"
$PN"Y31"73;
"DDR2_DQ<44>"
$PN"V35"74;
"DDR2_DQ<45>"
$PN"Y35"75;
"DDR2_DQ<46>"
$PN"U32"76;
"DDR2_DQ<47>"
$PN"AA32"77;
"DDR2_DQ<48>"
$PN"AD31"78;
"DDR2_DQ<49>"
$PN"AH31"79;
"DDR2_DQ<50>"
$PN"AE28"80;
"DDR2_DQ<51>"
$PN"AG28"81;
"DDR2_DQ<52>"
$PN"AE32"82;
"DDR2_DQ<53>"
$PN"AG32"83;
"DDR2_DQ<54>"
$PN"AD29"84;
"DDR2_DQ<55>"
$PN"AH29"85;
"DDR2_DQ<56>"
$PN"AD25"86;
"DDR2_DQ<57>"
$PN"AH25"87;
"DDR2_DQ<58>"
$PN"AE22"88;
"DDR2_DQ<59>"
$PN"AG22"89;
"DDR2_DQ<60>"
$PN"AE26"90;
"DDR2_DQ<61>"
$PN"AG26"91;
"DDR2_DQ<62>"
$PN"AD23"92;
"DDR2_DQ<63>"
$PN"AH23"93;
"DDR2_CS_N<0>"
$PN"V51"101;
"DDR2_CS_N<1>"
$PN"AB49"102;
"DDR2_CS_N<2>"
$PN"W46"103;
"DDR2_CS_N<3>"
$PN"AA46"104;
"DDR2_CS_N<4>"
$PN"AB51"105;
"DDR2_CS_N<5>"
$PN"W48"106;
"DDR2_CS_N<6>"
$PN"T45"107;
"DDR2_CS_N<7>"
$PN"V45"108;
"DDR2_CLK_DP<0>"
$PN"AB55"33;
"DDR2_CLK_DP<1>"
$PN"V55"34;
"DDR2_CLK_DP<2>"
$PN"AB57"35;
"DDR2_CLK_DP<3>"
$PN"V57"36;
"DDR2_CLK_DN<0>"
$PN"AA54"37;
"DDR2_CLK_DN<1>"
$PN"W54"38;
"DDR2_CLK_DN<2>"
$PN"AA56"39;
"DDR2_CLK_DN<3>"
$PN"W56"40;
"DDR2_CKE<0>"
$PN"AA62"109;
"DDR2_CKE<1>"
$PN"AD63"110;
"DDR2_CKE<2>"
$PN"V63"111;
"DDR2_CKE<3>"
$PN"AB63"112;
"DDR2_CID<2>"
$PN"AB45"13;
"DDR2_BG<0>"
$PN"AA60"113;
"DDR2_BG<1>"
$PN"AE62"114;
"DDR2_BA<0>"
$PN"W52"115;
"DDR2_BA<1>"
$PN"AE56"116;
"DDR2_ALERT_N"
$PN"AD61"157;
"DDR2_ACT_N"
$PN"AB61"158;
%"TAP"
"6","(-5575,1300)","0","mstr_standard","I18";
;
HDL_TAP"TRUE"
BODY_TYPE"PLUMBING"
CDS_LIB"mstr_standard";
"B \NAC \NWC"12;
"S \NAC"
BN"5"19;
%"TAP"
"6","(-5575,1350)","0","mstr_standard","I19";
;
HDL_TAP"TRUE"
BODY_TYPE"PLUMBING"
CDS_LIB"mstr_standard";
"B \NAC \NWC"12;
"S \NAC"
BN"6"20;
%"TAP"
"6","(-5575,1400)","0","mstr_standard","I20";
;
HDL_TAP"TRUE"
BODY_TYPE"PLUMBING"
CDS_LIB"mstr_standard";
"B \NAC \NWC"12;
"S \NAC"
BN"7"21;
%"TAP"
"6","(-5575,1500)","0","mstr_standard","I21";
;
HDL_TAP"TRUE"
BODY_TYPE"PLUMBING"
CDS_LIB"mstr_standard";
"B \NAC \NWC"9;
"S \NAC"
BN"0"22;
%"TAP"
"6","(-5575,1550)","0","mstr_standard","I22";
;
HDL_TAP"TRUE"
BODY_TYPE"PLUMBING"
CDS_LIB"mstr_standard";
"B \NAC \NWC"9;
"S \NAC"
BN"1"23;
%"TAP"
"6","(-5575,1600)","0","mstr_standard","I23";
;
HDL_TAP"TRUE"
BODY_TYPE"PLUMBING"
CDS_LIB"mstr_standard";
"B \NAC \NWC"9;
"S \NAC"
BN"2"24;
%"TAP"
"6","(-5575,1650)","0","mstr_standard","I24";
;
HDL_TAP"TRUE"
BODY_TYPE"PLUMBING"
CDS_LIB"mstr_standard";
"B \NAC \NWC"9;
"S \NAC"
BN"3"25;
%"TAP"
"6","(-5575,1700)","0","mstr_standard","I25";
;
HDL_TAP"TRUE"
BODY_TYPE"PLUMBING"
CDS_LIB"mstr_standard";
"B \NAC \NWC"9;
"S \NAC"
BN"4"26;
%"TAP"
"6","(-5575,1750)","0","mstr_standard","I26";
;
HDL_TAP"TRUE"
BODY_TYPE"PLUMBING"
CDS_LIB"mstr_standard";
"B \NAC \NWC"9;
"S \NAC"
BN"5"27;
%"TAP"
"6","(-5575,1800)","0","mstr_standard","I27";
;
HDL_TAP"TRUE"
BODY_TYPE"PLUMBING"
CDS_LIB"mstr_standard";
"B \NAC \NWC"9;
"S \NAC"
BN"6"28;
%"TAP"
"6","(-5575,1900)","0","mstr_standard","I28";
;
HDL_TAP"TRUE"
BODY_TYPE"PLUMBING"
CDS_LIB"mstr_standard";
"B \NAC \NWC"9;
"S \NAC"
BN"8"30;
%"TAP"
"6","(-5575,1850)","0","mstr_standard","I29";
;
HDL_TAP"TRUE"
BODY_TYPE"PLUMBING"
CDS_LIB"mstr_standard";
"B \NAC \NWC"9;
"S \NAC"
BN"7"29;
%"TAP"
"6","(-5575,1950)","0","mstr_standard","I31";
;
HDL_TAP"TRUE"
BODY_TYPE"PLUMBING"
CDS_LIB"mstr_standard";
"B \NAC \NWC"9;
"S \NAC"
BN"9"31;
%"TAP"
"6","(-5575,2000)","0","mstr_standard","I32";
;
HDL_TAP"TRUE"
BODY_TYPE"PLUMBING"
CDS_LIB"mstr_standard";
"B \NAC \NWC"9;
"S \NAC"
BN"10"32;
%"TAP"
"6","(-5575,2050)","0","mstr_standard","I33";
;
HDL_TAP"TRUE"
BODY_TYPE"PLUMBING"
CDS_LIB"mstr_standard";
"B \NAC \NWC"9;
"S \NAC"
BN"11"41;
%"TAP"
"6","(-5575,2100)","0","mstr_standard","I34";
;
HDL_TAP"TRUE"
BODY_TYPE"PLUMBING"
CDS_LIB"mstr_standard";
"B \NAC \NWC"9;
"S \NAC"
BN"12"42;
%"TAP"
"6","(-5575,2150)","0","mstr_standard","I35";
;
HDL_TAP"TRUE"
BODY_TYPE"PLUMBING"
CDS_LIB"mstr_standard";
"B \NAC \NWC"9;
"S \NAC"
BN"13"43;
%"TAP"
"6","(-5575,2200)","0","mstr_standard","I36";
;
HDL_TAP"TRUE"
BODY_TYPE"PLUMBING"
CDS_LIB"mstr_standard";
"B \NAC \NWC"9;
"S \NAC"
BN"14"44;
%"TAP"
"6","(-5575,2250)","0","mstr_standard","I37";
;
HDL_TAP"TRUE"
BODY_TYPE"PLUMBING"
CDS_LIB"mstr_standard";
"B \NAC \NWC"9;
"S \NAC"
BN"15"45;
%"TAP"
"6","(-5575,2300)","0","mstr_standard","I38";
;
HDL_TAP"TRUE"
BODY_TYPE"PLUMBING"
CDS_LIB"mstr_standard";
"B \NAC \NWC"9;
"S \NAC"
BN"16"46;
%"TAP"
"6","(-5575,2350)","0","mstr_standard","I39";
;
HDL_TAP"TRUE"
BODY_TYPE"PLUMBING"
CDS_LIB"mstr_standard";
"B \NAC \NWC"9;
"S \NAC"
BN"17"47;
%"TAP"
"6","(-5575,2400)","0","mstr_standard","I40";
;
HDL_TAP"TRUE"
BODY_TYPE"PLUMBING"
CDS_LIB"mstr_standard";
"B \NAC \NWC"9;
"S \NAC"
BN"18"48;
%"TAP"
"6","(-5575,2450)","0","mstr_standard","I41";
;
HDL_TAP"TRUE"
BODY_TYPE"PLUMBING"
CDS_LIB"mstr_standard";
"B \NAC \NWC"9;
"S \NAC"
BN"19"49;
%"TAP"
"6","(-5575,2500)","0","mstr_standard","I42";
;
HDL_TAP"TRUE"
BODY_TYPE"PLUMBING"
CDS_LIB"mstr_standard";
"B \NAC \NWC"9;
"S \NAC"
BN"20"50;
%"TAP"
"6","(-5575,2550)","0","mstr_standard","I43";
;
HDL_TAP"TRUE"
BODY_TYPE"PLUMBING"
CDS_LIB"mstr_standard";
"B \NAC \NWC"9;
"S \NAC"
BN"21"51;
%"TAP"
"6","(-5575,2600)","0","mstr_standard","I44";
;
HDL_TAP"TRUE"
BODY_TYPE"PLUMBING"
CDS_LIB"mstr_standard";
"B \NAC \NWC"9;
"S \NAC"
BN"22"52;
%"TAP"
"6","(-5575,2650)","0","mstr_standard","I45";
;
HDL_TAP"TRUE"
BODY_TYPE"PLUMBING"
CDS_LIB"mstr_standard";
"B \NAC \NWC"9;
"S \NAC"
BN"23"53;
%"TAP"
"6","(-5575,2700)","0","mstr_standard","I46";
;
HDL_TAP"TRUE"
BODY_TYPE"PLUMBING"
CDS_LIB"mstr_standard";
"B \NAC \NWC"9;
"S \NAC"
BN"24"54;
%"TAP"
"6","(-5575,2800)","0","mstr_standard","I47";
;
HDL_TAP"TRUE"
BODY_TYPE"PLUMBING"
CDS_LIB"mstr_standard";
"B \NAC \NWC"9;
"S \NAC"
BN"26"56;
%"TAP"
"6","(-5575,2750)","0","mstr_standard","I48";
;
HDL_TAP"TRUE"
BODY_TYPE"PLUMBING"
CDS_LIB"mstr_standard";
"B \NAC \NWC"9;
"S \NAC"
BN"25"55;
%"TAP"
"6","(-5575,2850)","0","mstr_standard","I49";
;
HDL_TAP"TRUE"
BODY_TYPE"PLUMBING"
CDS_LIB"mstr_standard";
"B \NAC \NWC"9;
"S \NAC"
BN"27"57;
%"TAP"
"6","(-5575,600)","0","mstr_standard","I5";
;
HDL_TAP"TRUE"
BODY_TYPE"PLUMBING"
CDS_LIB"mstr_standard";
"B \NAC \NWC"10;
"S \NAC"
BN"0"37;
%"TAP"
"6","(-5575,2900)","0","mstr_standard","I50";
;
HDL_TAP"TRUE"
BODY_TYPE"PLUMBING"
CDS_LIB"mstr_standard";
"B \NAC \NWC"9;
"S \NAC"
BN"28"58;
%"TAP"
"6","(-5575,2950)","0","mstr_standard","I51";
;
HDL_TAP"TRUE"
BODY_TYPE"PLUMBING"
CDS_LIB"mstr_standard";
"B \NAC \NWC"9;
"S \NAC"
BN"29"59;
%"TAP"
"6","(-5575,3050)","0","mstr_standard","I52";
;
HDL_TAP"TRUE"
BODY_TYPE"PLUMBING"
CDS_LIB"mstr_standard";
"B \NAC \NWC"9;
"S \NAC"
BN"31"61;
%"TAP"
"6","(-5575,3000)","0","mstr_standard","I53";
;
HDL_TAP"TRUE"
BODY_TYPE"PLUMBING"
CDS_LIB"mstr_standard";
"B \NAC \NWC"9;
"S \NAC"
BN"30"60;
%"TAP"
"6","(-5575,3100)","0","mstr_standard","I54";
;
HDL_TAP"TRUE"
BODY_TYPE"PLUMBING"
CDS_LIB"mstr_standard";
"B \NAC \NWC"9;
"S \NAC"
BN"32"62;
%"TAP"
"6","(-5575,3150)","0","mstr_standard","I55";
;
HDL_TAP"TRUE"
BODY_TYPE"PLUMBING"
CDS_LIB"mstr_standard";
"B \NAC \NWC"9;
"S \NAC"
BN"33"63;
%"TAP"
"6","(-5575,3200)","0","mstr_standard","I56";
;
HDL_TAP"TRUE"
BODY_TYPE"PLUMBING"
CDS_LIB"mstr_standard";
"B \NAC \NWC"9;
"S \NAC"
BN"34"64;
%"TAP"
"6","(-5575,3300)","0","mstr_standard","I57";
;
HDL_TAP"TRUE"
BODY_TYPE"PLUMBING"
CDS_LIB"mstr_standard";
"B \NAC \NWC"9;
"S \NAC"
BN"36"66;
%"TAP"
"6","(-5575,3250)","0","mstr_standard","I58";
;
HDL_TAP"TRUE"
BODY_TYPE"PLUMBING"
CDS_LIB"mstr_standard";
"B \NAC \NWC"9;
"S \NAC"
BN"35"65;
%"TAP"
"6","(-5575,3350)","0","mstr_standard","I59";
;
HDL_TAP"TRUE"
BODY_TYPE"PLUMBING"
CDS_LIB"mstr_standard";
"B \NAC \NWC"9;
"S \NAC"
BN"37"67;
%"TAP"
"6","(-5575,650)","0","mstr_standard","I6";
;
HDL_TAP"TRUE"
BODY_TYPE"PLUMBING"
CDS_LIB"mstr_standard";
"B \NAC \NWC"10;
"S \NAC"
BN"1"38;
%"TAP"
"6","(-5575,3400)","0","mstr_standard","I60";
;
HDL_TAP"TRUE"
BODY_TYPE"PLUMBING"
CDS_LIB"mstr_standard";
"B \NAC \NWC"9;
"S \NAC"
BN"38"68;
%"TAP"
"6","(-5575,3450)","0","mstr_standard","I61";
;
HDL_TAP"TRUE"
BODY_TYPE"PLUMBING"
CDS_LIB"mstr_standard";
"B \NAC \NWC"9;
"S \NAC"
BN"39"69;
%"TAP"
"6","(-5575,3500)","0","mstr_standard","I62";
;
HDL_TAP"TRUE"
BODY_TYPE"PLUMBING"
CDS_LIB"mstr_standard";
"B \NAC \NWC"9;
"S \NAC"
BN"40"70;
%"TAP"
"6","(-5575,3550)","0","mstr_standard","I63";
;
HDL_TAP"TRUE"
BODY_TYPE"PLUMBING"
CDS_LIB"mstr_standard";
"B \NAC \NWC"9;
"S \NAC"
BN"41"71;
%"TAP"
"6","(-5575,3600)","0","mstr_standard","I64";
;
HDL_TAP"TRUE"
BODY_TYPE"PLUMBING"
CDS_LIB"mstr_standard";
"B \NAC \NWC"9;
"S \NAC"
BN"42"72;
%"TAP"
"6","(-5575,3650)","0","mstr_standard","I65";
;
HDL_TAP"TRUE"
BODY_TYPE"PLUMBING"
CDS_LIB"mstr_standard";
"B \NAC \NWC"9;
"S \NAC"
BN"43"73;
%"TAP"
"6","(-5575,3700)","0","mstr_standard","I66";
;
HDL_TAP"TRUE"
BODY_TYPE"PLUMBING"
CDS_LIB"mstr_standard";
"B \NAC \NWC"9;
"S \NAC"
BN"44"74;
%"TAP"
"6","(-5575,3750)","0","mstr_standard","I67";
;
HDL_TAP"TRUE"
BODY_TYPE"PLUMBING"
CDS_LIB"mstr_standard";
"B \NAC \NWC"9;
"S \NAC"
BN"45"75;
%"TAP"
"6","(-5575,3800)","0","mstr_standard","I68";
;
HDL_TAP"TRUE"
BODY_TYPE"PLUMBING"
CDS_LIB"mstr_standard";
"B \NAC \NWC"9;
"S \NAC"
BN"46"76;
%"TAP"
"6","(-5575,3850)","0","mstr_standard","I69";
;
HDL_TAP"TRUE"
BODY_TYPE"PLUMBING"
CDS_LIB"mstr_standard";
"B \NAC \NWC"9;
"S \NAC"
BN"47"77;
%"TAP"
"6","(-5575,750)","0","mstr_standard","I7";
;
HDL_TAP"TRUE"
BODY_TYPE"PLUMBING"
CDS_LIB"mstr_standard";
"B \NAC \NWC"10;
"S \NAC"
BN"3"40;
%"TAP"
"6","(-5575,3900)","0","mstr_standard","I70";
;
HDL_TAP"TRUE"
BODY_TYPE"PLUMBING"
CDS_LIB"mstr_standard";
"B \NAC \NWC"9;
"S \NAC"
BN"48"78;
%"TAP"
"6","(-5575,3950)","0","mstr_standard","I71";
;
HDL_TAP"TRUE"
BODY_TYPE"PLUMBING"
CDS_LIB"mstr_standard";
"B \NAC \NWC"9;
"S \NAC"
BN"49"79;
%"TAP"
"6","(-5575,4000)","0","mstr_standard","I73";
;
HDL_TAP"TRUE"
BODY_TYPE"PLUMBING"
CDS_LIB"mstr_standard";
"B \NAC \NWC"9;
"S \NAC"
BN"50"80;
%"TAP"
"6","(-5575,4050)","0","mstr_standard","I74";
;
HDL_TAP"TRUE"
BODY_TYPE"PLUMBING"
CDS_LIB"mstr_standard";
"B \NAC \NWC"9;
"S \NAC"
BN"51"81;
%"TAP"
"6","(-5575,4100)","0","mstr_standard","I75";
;
HDL_TAP"TRUE"
BODY_TYPE"PLUMBING"
CDS_LIB"mstr_standard";
"B \NAC \NWC"9;
"S \NAC"
BN"52"82;
%"TAP"
"6","(-5575,4150)","0","mstr_standard","I76";
;
HDL_TAP"TRUE"
BODY_TYPE"PLUMBING"
CDS_LIB"mstr_standard";
"B \NAC \NWC"9;
"S \NAC"
BN"53"83;
%"TAP"
"6","(-5575,4200)","0","mstr_standard","I77";
;
HDL_TAP"TRUE"
BODY_TYPE"PLUMBING"
CDS_LIB"mstr_standard";
"B \NAC \NWC"9;
"S \NAC"
BN"54"84;
%"TAP"
"6","(-5575,4250)","0","mstr_standard","I78";
;
HDL_TAP"TRUE"
BODY_TYPE"PLUMBING"
CDS_LIB"mstr_standard";
"B \NAC \NWC"9;
"S \NAC"
BN"55"85;
%"TAP"
"6","(-5575,4300)","0","mstr_standard","I79";
;
HDL_TAP"TRUE"
BODY_TYPE"PLUMBING"
CDS_LIB"mstr_standard";
"B \NAC \NWC"9;
"S \NAC"
BN"56"86;
%"TAP"
"6","(-5575,700)","0","mstr_standard","I8";
;
HDL_TAP"TRUE"
BODY_TYPE"PLUMBING"
CDS_LIB"mstr_standard";
"B \NAC \NWC"10;
"S \NAC"
BN"2"39;
%"TAP"
"6","(-5575,4350)","0","mstr_standard","I80";
;
HDL_TAP"TRUE"
BODY_TYPE"PLUMBING"
CDS_LIB"mstr_standard";
"B \NAC \NWC"9;
"S \NAC"
BN"57"87;
%"TAP"
"6","(-5575,4400)","0","mstr_standard","I81";
;
HDL_TAP"TRUE"
BODY_TYPE"PLUMBING"
CDS_LIB"mstr_standard";
"B \NAC \NWC"9;
"S \NAC"
BN"58"88;
%"TAP"
"6","(-5575,4450)","0","mstr_standard","I82";
;
HDL_TAP"TRUE"
BODY_TYPE"PLUMBING"
CDS_LIB"mstr_standard";
"B \NAC \NWC"9;
"S \NAC"
BN"59"89;
%"TAP"
"6","(-5575,4500)","0","mstr_standard","I83";
;
HDL_TAP"TRUE"
BODY_TYPE"PLUMBING"
CDS_LIB"mstr_standard";
"B \NAC \NWC"9;
"S \NAC"
BN"60"90;
%"TAP"
"6","(-5575,4550)","0","mstr_standard","I84";
;
HDL_TAP"TRUE"
BODY_TYPE"PLUMBING"
CDS_LIB"mstr_standard";
"B \NAC \NWC"9;
"S \NAC"
BN"61"91;
%"TAP"
"6","(-5575,4600)","0","mstr_standard","I85";
;
HDL_TAP"TRUE"
BODY_TYPE"PLUMBING"
CDS_LIB"mstr_standard";
"B \NAC \NWC"9;
"S \NAC"
BN"62"92;
%"TAP"
"6","(-5575,4650)","0","mstr_standard","I86";
;
HDL_TAP"TRUE"
BODY_TYPE"PLUMBING"
CDS_LIB"mstr_standard";
"B \NAC \NWC"9;
"S \NAC"
BN"63"93;
%"TAP"
"6","(-2850,750)","2","mstr_standard","I87";
;
HDL_TAP"TRUE"
BODY_TYPE"PLUMBING"
CDS_LIB"mstr_standard";
"B \NAC \NWC"4;
"S \NAC"
BN"1"116;
%"TAP"
"6","(-2850,700)","2","mstr_standard","I88";
;
HDL_TAP"TRUE"
BODY_TYPE"PLUMBING"
CDS_LIB"mstr_standard";
"B \NAC \NWC"4;
"S \NAC"
BN"0"115;
%"TAP"
"6","(-2850,800)","2","mstr_standard","I89";
;
HDL_TAP"TRUE"
BODY_TYPE"PLUMBING"
CDS_LIB"mstr_standard";
"B \NAC \NWC"5;
"S \NAC"
BN"0"113;
%"TAP"
"6","(-5575,850)","0","mstr_standard","I9";
;
HDL_TAP"TRUE"
BODY_TYPE"PLUMBING"
CDS_LIB"mstr_standard";
"B \NAC \NWC"11;
"S \NAC"
BN"1"34;
%"TAP"
"6","(-2850,850)","2","mstr_standard","I90";
;
HDL_TAP"TRUE"
BODY_TYPE"PLUMBING"
CDS_LIB"mstr_standard";
"B \NAC \NWC"5;
"S \NAC"
BN"1"114;
%"TAP"
"6","(-2850,1050)","2","mstr_standard","I91";
;
HDL_TAP"TRUE"
BODY_TYPE"PLUMBING"
CDS_LIB"mstr_standard";
"B \NAC \NWC"7;
"S \NAC"
BN"2"103;
%"TAP"
"6","(-2850,1000)","2","mstr_standard","I92";
;
HDL_TAP"TRUE"
BODY_TYPE"PLUMBING"
CDS_LIB"mstr_standard";
"B \NAC \NWC"7;
"S \NAC"
BN"1"102;
%"TAP"
"6","(-2850,950)","2","mstr_standard","I93";
;
HDL_TAP"TRUE"
BODY_TYPE"PLUMBING"
CDS_LIB"mstr_standard";
"B \NAC \NWC"7;
"S \NAC"
BN"0"101;
%"TAP"
"6","(-2850,1150)","2","mstr_standard","I94";
;
HDL_TAP"TRUE"
BODY_TYPE"PLUMBING"
CDS_LIB"mstr_standard";
"B \NAC \NWC"7;
"S \NAC"
BN"4"105;
%"TAP"
"6","(-2850,1100)","2","mstr_standard","I95";
;
HDL_TAP"TRUE"
BODY_TYPE"PLUMBING"
CDS_LIB"mstr_standard";
"B \NAC \NWC"7;
"S \NAC"
BN"3"104;
%"TAP"
"6","(-2850,1200)","2","mstr_standard","I96";
;
HDL_TAP"TRUE"
BODY_TYPE"PLUMBING"
CDS_LIB"mstr_standard";
"B \NAC \NWC"7;
"S \NAC"
BN"5"106;
%"TAP"
"6","(-2850,1250)","2","mstr_standard","I97";
;
HDL_TAP"TRUE"
BODY_TYPE"PLUMBING"
CDS_LIB"mstr_standard";
"B \NAC \NWC"7;
"S \NAC"
BN"6"107;
%"TAP"
"6","(-2850,1300)","2","mstr_standard","I98";
;
HDL_TAP"TRUE"
BODY_TYPE"PLUMBING"
CDS_LIB"mstr_standard";
"B \NAC \NWC"7;
"S \NAC"
BN"7"108;
%"TAP"
"6","(-2850,1400)","2","mstr_standard","I99";
;
HDL_TAP"TRUE"
BODY_TYPE"PLUMBING"
CDS_LIB"mstr_standard";
"B \NAC \NWC"8;
"S \NAC"
BN"0"94;
END.
